(kicad_pcb
	(version 20241229)
	(generator "pcbnew")
	(generator_version "9.0")
	(general
		(thickness 1.711)
		(legacy_teardrops no)
	)
	(paper "A4")
	(title_block
		(title "Antmicro Baseboard for Jetson AGX Thor")
		(date "2026-02-18")
		(rev "1.1.0")
		(company "Antmicro Ltd")
		(comment 1 "www.antmicro.com")
		(comment 9 "footprints 174-177 of 1170")
	)
	(layers
		(0 "F.Cu" signal)
		(4 "In1.Cu" signal)
		(6 "In2.Cu" signal)
		(8 "In3.Cu" signal)
		(10 "In4.Cu" jumper)
		(12 "In5.Cu" signal)
		(14 "In6.Cu" signal)
		(16 "In7.Cu" signal)
		(18 "In8.Cu" signal)
		(2 "B.Cu" signal)
		(9 "F.Adhes" user "F.Adhesive")
		(11 "B.Adhes" user "B.Adhesive")
		(13 "F.Paste" user)
		(15 "B.Paste" user)
		(5 "F.SilkS" user "F.Silkscreen")
		(7 "B.SilkS" user "B.Silkscreen")
		(1 "F.Mask" user)
		(3 "B.Mask" user)
		(17 "Dwgs.User" user "User.Drawings")
		(19 "Cmts.User" user "User.Comments")
		(21 "Eco1.User" user "User.Eco1")
		(23 "Eco2.User" user "User.Eco2")
		(25 "Edge.Cuts" user)
		(27 "Margin" user)
		(31 "F.CrtYd" user "F.Courtyard")
		(29 "B.CrtYd" user "B.Courtyard")
		(35 "F.Fab" user)
		(33 "B.Fab" user)
	)
	(footprint "antmicro-footprints:LED_0603_1608Metric_G"
		(layer "F.Cu")
		(at 190.676 140.1 180)
		(descr "LED SMD 0603 Green")
		(tags "LED SMD 0603 Green")
		(property "Reference" "D14"
			(at -0.95 1.6 0)
			(layer "F.SilkS")
			(effects
				(font
					(size 0.7 0.7)
					(thickness 0.15)
				)
				(justify right top)
			)
		)
		(property "Value" "LED_G_0603_LTST-C190GKT"
			(at -0.001 1.599 0)
			(layer "F.Fab")
			(effects
				(font
					(size 0.7 0.7)
					(thickness 0.15)
				)
				(justify right top)
			)
		)
		(property "Datasheet" "https://media.digikey.com/pdf/Data%20Sheets/Lite-On%20PDFs/LTST-C190GKT.pdf"
			(at 0 0 0)
			(layer "F.Fab")
			(hide yes)
			(effects
				(font
					(size 1.27 1.27)
					(thickness 0.15)
				)
			)
		)
		(property "Description" "LED, Green, SMD, 0603, 20 mA, 2.1 V, 569 nm"
			(at 0 0 0)
			(layer "F.Fab")
			(hide yes)
			(effects
				(font
					(size 1.27 1.27)
					(thickness 0.15)
				)
			)
		)
		(property "MPN" "LTST-C190GKT"
			(at 0 0 180)
			(unlocked yes)
			(layer "F.Fab")
			(hide yes)
			(effects
				(font
					(size 1 1)
					(thickness 0.15)
				)
			)
		)
		(property "Manufacturer" "Lite-On"
			(at 0 0 180)
			(unlocked yes)
			(layer "F.Fab")
			(hide yes)
			(effects
				(font
					(size 1 1)
					(thickness 0.15)
				)
			)
		)
		(property "Author" "Antmicro"
			(at 0 0 180)
			(unlocked yes)
			(layer "F.Fab")
			(hide yes)
			(effects
				(font
					(size 1 1)
					(thickness 0.15)
				)
			)
		)
		(property "License" "Apache-2.0"
			(at 0 0 180)
			(unlocked yes)
			(layer "F.Fab")
			(hide yes)
			(effects
				(font
					(size 1 1)
					(thickness 0.15)
				)
			)
		)
		(property "Color" "Green"
			(at 0 0 180)
			(unlocked yes)
			(layer "F.Fab")
			(hide yes)
			(effects
				(font
					(size 1 1)
					(thickness 0.15)
				)
			)
		)
		(sheetname "/SFP/")
		(sheetfile "sfp.kicad_sch")
		(attr smd)
		(fp_line
			(start 0.22 0.35)
			(end -0.22 0.35)
			(stroke
				(width 0.15)
				(type solid)
			)
			(layer "F.SilkS")
		)
		(fp_line
			(start 0.22 -0.35)
			(end -0.22 -0.35)
			(stroke
				(width 0.15)
				(type solid)
			)
			(layer "F.SilkS")
		)
		(fp_line
			(start 0.105328 0.201008)
			(end 0.105329 -0.198992)
			(stroke
				(width 0.1)
				(type solid)
			)
			(layer "F.SilkS")
		)
		(fp_line
			(start 0.105328 0.201008)
			(end -0.094672 0.001008)
			(stroke
				(width 0.1)
				(type solid)
			)
			(layer "F.SilkS")
		)
		(fp_line
			(start 0.105328 0.001008)
			(end 0.240001 0.001)
			(stroke
				(width 0.1)
				(type solid)
			)
			(layer "F.SilkS")
		)
		(fp_line
			(start -0.094672 0.201008)
			(end -0.094672 -0.198992)
			(stroke
				(width 0.1)
				(type solid)
			)
			(layer "F.SilkS")
		)
		(fp_line
			(start -0.094672 0.001008)
			(end 0.105329 -0.198992)
			(stroke
				(width 0.1)
				(type solid)
			)
			(layer "F.SilkS")
		)
		(fp_line
			(start -0.094672 0.001008)
			(end -0.24 0.001008)
			(stroke
				(width 0.1)
				(type solid)
			)
			(layer "F.SilkS")
		)
		(fp_line
			(start -1.18 -0.319)
			(end -1.18 0.321)
			(stroke
				(width 0.15)
				(type solid)
			)
			(layer "F.SilkS")
		)
		(fp_poly
			(pts
				(xy 1.25 0.65) (xy -1.25 0.65) (xy -1.25 -0.65) (xy 1.25 -0.65)
			)
			(stroke
				(width 0.05)
				(type solid)
			)
			(fill no)
			(layer "F.CrtYd")
		)
		(fp_line
			(start 0.599 0)
			(end 0.200999 0)
			(stroke
				(width 0.15)
				(type solid)
			)
			(layer "F.Fab")
		)
		(fp_line
			(start 0.201 0.2)
			(end 0.200999 0)
			(stroke
				(width 0.15)
				(type solid)
			)
			(layer "F.Fab")
		)
		(fp_line
			(start 0.201 -0.202)
			(end -0.101 0)
			(stroke
				(width 0.15)
				(type solid)
			)
			(layer "F.Fab")
		)
		(fp_line
			(start 0.200999 0)
			(end 0.201 -0.202)
			(stroke
				(width 0.15)
				(type solid)
			)
			(layer "F.Fab")
		)
		(fp_line
			(start -0.101 0)
			(end 0.201 0.2)
			(stroke
				(width 0.15)
				(type solid)
			)
			(layer "F.Fab")
		)
		(fp_line
			(start -0.199 0.2)
			(end -0.199 0.1)
			(stroke
				(width 0.15)
				(type solid)
			)
			(layer "F.Fab")
		)
		(fp_line
			(start -0.199 0)
			(end -0.597 0)
			(stroke
				(width 0.15)
				(type solid)
			)
			(layer "F.Fab")
		)
		(fp_line
			(start -0.199 -0.202)
			(end -0.199 0.1)
			(stroke
				(width 0.15)
				(type solid)
			)
			(layer "F.Fab")
		)
		(fp_poly
			(pts
				(xy 0.848 0.4) (xy -0.85 0.4) (xy -0.85 -0.402) (xy 0.848 -0.401999)
			)
			(stroke
				(width 0.15)
				(type solid)
			)
			(fill no)
			(layer "F.Fab")
		)
		(fp_text user "Author: Antmicro"
			(at -1.4224 4.799 0)
			(layer "F.Fab")
			(effects
				(font
					(size 0.7 0.7)
					(thickness 0.15)
				)
				(justify right top)
			)
		)
		(fp_text user "${REFERENCE}"
			(at -1.4224 5.999 0)
			(layer "F.Fab")
			(effects
				(font
					(size 0.7 0.7)
					(thickness 0.15)
				)
				(justify right top)
			)
		)
		(fp_text user "License: Apache-2.0"
			(at -1.4224 3.599 0)
			(layer "F.Fab")
			(effects
				(font
					(size 0.7 0.7)
					(thickness 0.15)
				)
				(justify right top)
			)
		)
		(pad "1" smd roundrect
			(at -0.7 0)
			(size 0.8 1)
			(layers "F.Cu" "F.Mask" "F.Paste")
			(roundrect_rratio 0.2)
			(net 530 "Net-(D14-C)")
			(pinfunction "C")
			(pintype "passive")
		)
		(pad "2" smd roundrect
			(at 0.7 0)
			(size 0.8 1)
			(layers "F.Cu" "F.Mask" "F.Paste")
			(roundrect_rratio 0.2)
			(net 2 "+3V3")
			(pinfunction "A")
			(pintype "passive")
		)
	)
	(footprint "antmicro-footprints:C_0402_1005Metric"
		(layer "F.Cu")
		(at 203.1 117.9 -90)
		(descr "Capacitor SMD 0402")
		(tags "capacitor SMD 0402")
		(property "Reference" "C94"
			(at -3 0.4 90)
			(layer "F.SilkS")
			(effects
				(font
					(size 0.7 0.7)
					(thickness 0.15)
				)
				(justify right top)
			)
		)
		(property "Value" "C_100n_0402"
			(at -1.022927 2.155213 90)
			(layer "F.Fab")
			(effects
				(font
					(size 0.7 0.7)
					(thickness 0.15)
				)
				(justify right top)
			)
		)
		(property "Datasheet" "https://www.murata.com/products/productdetail?partno=GRM155R61H104KE14%23"
			(at 0 0 90)
			(layer "F.Fab")
			(hide yes)
			(effects
				(font
					(size 1.27 1.27)
					(thickness 0.15)
				)
			)
		)
		(property "Description" "SMD Multilayer Ceramic Capacitor, 0.1 µF, 50 V, 0402 [1005 Metric], ± 10%, X5R, GRM Series"
			(at 0 0 90)
			(layer "F.Fab")
			(hide yes)
			(effects
				(font
					(size 1.27 1.27)
					(thickness 0.15)
				)
			)
		)
		(property "MPN" "GRM155R61H104KE14D"
			(at 0 0 270)
			(unlocked yes)
			(layer "F.Fab")
			(hide yes)
			(effects
				(font
					(size 1 1)
					(thickness 0.15)
				)
			)
		)
		(property "Val" "100n"
			(at 0 0 270)
			(unlocked yes)
			(layer "F.Fab")
			(hide yes)
			(effects
				(font
					(size 1 1)
					(thickness 0.15)
				)
			)
		)
		(property "Voltage" "50V"
			(at 0 0 270)
			(unlocked yes)
			(layer "F.Fab")
			(hide yes)
			(effects
				(font
					(size 1 1)
					(thickness 0.15)
				)
			)
		)
		(property "Dielectric" "X5R"
			(at 0 0 270)
			(unlocked yes)
			(layer "F.Fab")
			(hide yes)
			(effects
				(font
					(size 1 1)
					(thickness 0.15)
				)
			)
		)
		(property "Manufacturer" "Murata"
			(at 0 0 270)
			(unlocked yes)
			(layer "F.Fab")
			(hide yes)
			(effects
				(font
					(size 1 1)
					(thickness 0.15)
				)
			)
		)
		(property "License" "Apache-2.0"
			(at 0 0 270)
			(unlocked yes)
			(layer "F.Fab")
			(hide yes)
			(effects
				(font
					(size 1 1)
					(thickness 0.15)
				)
			)
		)
		(property "Author" "Antmicro"
			(at 0 0 270)
			(unlocked yes)
			(layer "F.Fab")
			(hide yes)
			(effects
				(font
					(size 1 1)
					(thickness 0.15)
				)
			)
		)
		(sheetname "/USB Hub/")
		(sheetfile "usb_hub.kicad_sch")
		(attr smd)
		(fp_poly
			(pts
				(xy -0.925 -0.47) (xy 0.925 -0.47) (xy 0.925 0.47) (xy -0.925 0.47)
			)
			(stroke
				(width 0.05)
				(type default)
			)
			(fill no)
			(layer "F.CrtYd")
		)
		(fp_line
			(start -0.494 0.248)
			(end -0.494 -0.25)
			(stroke
				(width 0.15)
				(type solid)
			)
			(layer "F.Fab")
		)
		(fp_line
			(start 0.504 0.248)
			(end -0.494 0.248)
			(stroke
				(width 0.15)
				(type solid)
			)
			(layer "F.Fab")
		)
		(fp_line
			(start -0.494 -0.25)
			(end 0.504 -0.25)
			(stroke
				(width 0.15)
				(type solid)
			)
			(layer "F.Fab")
		)
		(fp_line
			(start 0.504 -0.25)
			(end 0.504 0.248)
			(stroke
				(width 0.15)
				(type solid)
			)
			(layer "F.Fab")
		)
		(fp_text user "${REFERENCE}"
			(at -0.939 4.599 90)
			(layer "F.Fab")
			(effects
				(font
					(size 0.7 0.7)
					(thickness 0.15)
				)
				(justify right top)
			)
		)
		(fp_text user "License: Apache-2.0"
			(at -0.939 5.799 90)
			(layer "F.Fab")
			(effects
				(font
					(size 0.7 0.7)
					(thickness 0.15)
				)
				(justify right top)
			)
		)
		(fp_text user "Author: Antmicro"
			(at -0.939 3.399 90)
			(layer "F.Fab")
			(effects
				(font
					(size 0.7 0.7)
					(thickness 0.15)
				)
				(justify right top)
			)
		)
		(pad "1" smd roundrect
			(at -0.48 0 270)
			(size 0.59 0.64)
			(layers "F.Cu" "F.Mask" "F.Paste")
			(roundrect_rratio 0.25)
			(net 1 "GND")
			(pintype "passive")
		)
		(pad "2" smd roundrect
			(at 0.48 0 270)
			(size 0.59 0.64)
			(layers "F.Cu" "F.Mask" "F.Paste")
			(roundrect_rratio 0.25)
			(net 2 "+3V3")
			(pintype "passive")
		)
	)
	(footprint "antmicro-footprints:R_0402_1005Metric"
		(layer "F.Cu")
		(at 147.8 118.2)
		(descr "Resistor SMD 0402")
		(tags "resistor SMD 0402")
		(property "Reference" "R362"
			(at -3.7 0.5 0)
			(layer "F.SilkS")
			(effects
				(font
					(size 0.7 0.7)
					(thickness 0.15)
				)
				(justify left bottom)
			)
		)
		(property "Value" "R_2k2_0402"
			(at -1.011843 1.772047 0)
			(layer "F.Fab")
			(effects
				(font
					(size 0.7 0.7)
					(thickness 0.15)
				)
				(justify left bottom)
			)
		)
		(property "Datasheet" "https://www.bourns.com/docs/product-datasheets/cr.pdf"
			(at 0 0 0)
			(layer "F.Fab")
			(hide yes)
			(effects
				(font
					(size 1.27 1.27)
					(thickness 0.15)
				)
			)
		)
		(property "Description" "SMD Chip Resistor, 2.2 kohm, ± 1%, 62.5 mW, 0402 [1005 Metric], Thick Film, General Purpose"
			(at 0 0 0)
			(layer "F.Fab")
			(hide yes)
			(effects
				(font
					(size 1.27 1.27)
					(thickness 0.15)
				)
			)
		)
		(property "MPN" "CR0402-FX-2201GLF"
			(at 0 0 0)
			(unlocked yes)
			(layer "F.Fab")
			(hide yes)
			(effects
				(font
					(size 1 1)
					(thickness 0.15)
				)
			)
		)
		(property "Manufacturer" "Bourns"
			(at 0 0 0)
			(unlocked yes)
			(layer "F.Fab")
			(hide yes)
			(effects
				(font
					(size 1 1)
					(thickness 0.15)
				)
			)
		)
		(property "License" "Apache-2.0"
			(at 0 0 0)
			(unlocked yes)
			(layer "F.Fab")
			(hide yes)
			(effects
				(font
					(size 1 1)
					(thickness 0.15)
				)
			)
		)
		(property "Author" "Antmicro"
			(at 0 0 0)
			(unlocked yes)
			(layer "F.Fab")
			(hide yes)
			(effects
				(font
					(size 1 1)
					(thickness 0.15)
				)
			)
		)
		(property "Val" "2k2"
			(at 0 0 0)
			(unlocked yes)
			(layer "F.Fab")
			(hide yes)
			(effects
				(font
					(size 1 1)
					(thickness 0.15)
				)
			)
		)
		(property "Tolerance" "1%"
			(at 0 0 0)
			(unlocked yes)
			(layer "F.Fab")
			(hide yes)
			(effects
				(font
					(size 1 1)
					(thickness 0.15)
				)
			)
		)
		(sheetname "/SoM_IO/")
		(sheetfile "som_io.kicad_sch")
		(attr smd)
		(fp_rect
			(start -0.925 -0.47)
			(end 0.925 0.47)
			(stroke
				(width 0.05)
				(type default)
			)
			(fill no)
			(layer "F.CrtYd")
		)
		(fp_rect
			(start -0.5 -0.25)
			(end 0.5 0.25)
			(stroke
				(width 0.15)
				(type solid)
			)
			(fill no)
			(layer "F.Fab")
		)
		(fp_text user "${REFERENCE}"
			(at -0.95 3.168 0)
			(layer "F.Fab")
			(effects
				(font
					(size 0.7 0.7)
					(thickness 0.15)
				)
				(justify left bottom)
			)
		)
		(fp_text user "License: Apache-2.0"
			(at -0.95 5.169 0)
			(layer "F.Fab")
			(effects
				(font
					(size 0.7 0.7)
					(thickness 0.15)
				)
				(justify left bottom)
			)
		)
		(fp_text user "Author: Antmicro"
			(at -0.95 4.169 0)
			(layer "F.Fab")
			(effects
				(font
					(size 0.7 0.7)
					(thickness 0.15)
				)
				(justify left bottom)
			)
		)
		(pad "1" smd roundrect
			(at -0.48 0)
			(size 0.59 0.64)
			(layers "F.Cu" "F.Mask" "F.Paste")
			(roundrect_rratio 0.25)
			(net 2 "+3V3")
			(pintype "passive")
		)
		(pad "2" smd roundrect
			(at 0.48 0)
			(size 0.59 0.64)
			(layers "F.Cu" "F.Mask" "F.Paste")
			(roundrect_rratio 0.25)
			(net 999 "/SFP/I2C_{SFP}.SDA")
			(pintype "passive")
		)
	)
	(footprint "antmicro-footprints:SOT-523"
		(layer "F.Cu")
		(at 143.26 133.44 -90)
		(property "Reference" "Q38"
			(at -1.14 7.06 90)
			(layer "F.SilkS")
			(effects
				(font
					(size 0.7 0.7)
					(thickness 0.15)
				)
				(justify right top)
			)
		)
		(property "Value" "DMG1012T-7"
			(at 0.1 1.824 90)
			(layer "F.Fab")
			(effects
				(font
					(size 0.7 0.7)
					(thickness 0.15)
				)
				(justify right top)
			)
		)
		(property "Datasheet" "https://www.diodes.com/assets/Datasheets/ds31783.pdf"
			(at 0 0 90)
			(layer "F.Fab")
			(hide yes)
			(effects
				(font
					(size 1.27 1.27)
					(thickness 0.15)
				)
			)
		)
		(property "Description" "Power MOSFET, N Channel, 20 V, 630 mA, 0.3 ohm, SOT-523, Surface Mount"
			(at 0 0 90)
			(layer "F.Fab")
			(hide yes)
			(effects
				(font
					(size 1.27 1.27)
					(thickness 0.15)
				)
			)
		)
		(property "MPN" "DMG1012T-7"
			(at 0 0 270)
			(unlocked yes)
			(layer "F.Fab")
			(hide yes)
			(effects
				(font
					(size 1 1)
					(thickness 0.15)
				)
			)
		)
		(property "Manufacturer" "Diodes Incorporated"
			(at 0 0 270)
			(unlocked yes)
			(layer "F.Fab")
			(hide yes)
			(effects
				(font
					(size 1 1)
					(thickness 0.15)
				)
			)
		)
		(property "Author" "Antmicro"
			(at 0 0 270)
			(unlocked yes)
			(layer "F.Fab")
			(hide yes)
			(effects
				(font
					(size 1 1)
					(thickness 0.15)
				)
			)
		)
		(property "License" "Apache-2.0"
			(at 0 0 270)
			(unlocked yes)
			(layer "F.Fab")
			(hide yes)
			(effects
				(font
					(size 1 1)
					(thickness 0.15)
				)
			)
		)
		(sheetname "/SoM_Power/")
		(sheetfile "som_power.kicad_sch")
		(attr smd)
		(fp_line
			(start -0.927 -0.051)
			(end -0.927 -0.351)
			(stroke
				(width 0.15)
				(type solid)
			)
			(layer "F.SilkS")
		)
		(fp_line
			(start -0.927 -0.351)
			(end -0.725 -0.551)
			(stroke
				(width 0.15)
				(type solid)
			)
			(layer "F.SilkS")
		)
		(fp_line
			(start -0.725 -0.551)
			(end -0.277 -0.551)
			(stroke
				(width 0.15)
				(type solid)
			)
			(layer "F.SilkS")
		)
		(fp_line
			(start -0.277 -0.551)
			(end -0.277 -0.75)
			(stroke
				(width 0.15)
				(type solid)
			)
			(layer "F.SilkS")
		)
		(fp_circle
			(center -0.9652 0.9652)
			(end -0.9152 0.9652)
			(stroke
				(width 0.15)
				(type solid)
			)
			(fill yes)
			(layer "F.SilkS")
		)
		(fp_line
			(start -1.12 1.15)
			(end 1.1 1.15)
			(stroke
				(width 0.05)
				(type solid)
			)
			(layer "F.CrtYd")
		)
		(fp_line
			(start -1.12 -1.16)
			(end -1.12 1.15)
			(stroke
				(width 0.05)
				(type solid)
			)
			(layer "F.CrtYd")
		)
		(fp_line
			(start -1.12 -1.16)
			(end 1.1 -1.16)
			(stroke
				(width 0.05)
				(type solid)
			)
			(layer "F.CrtYd")
		)
		(fp_line
			(start 1.1 -1.16)
			(end 1.1 1.15)
			(stroke
				(width 0.05)
				(type solid)
			)
			(layer "F.CrtYd")
		)
		(fp_line
			(start 0.8 0.424)
			(end -0.802 0.424)
			(stroke
				(width 0.15)
				(type solid)
			)
			(layer "F.Fab")
		)
		(fp_line
			(start -0.802 -0.276)
			(end -0.802 0.424)
			(stroke
				(width 0.15)
				(type solid)
			)
			(layer "F.Fab")
		)
		(fp_line
			(start -0.652 -0.425)
			(end -0.802 -0.276)
			(stroke
				(width 0.15)
				(type solid)
			)
			(layer "F.Fab")
		)
		(fp_line
			(start 0.8 -0.425)
			(end 0.8 0.424)
			(stroke
				(width 0.15)
				(type solid)
			)
			(layer "F.Fab")
		)
		(fp_line
			(start 0.8 -0.425)
			(end -0.652 -0.425)
			(stroke
				(width 0.15)
				(type solid)
			)
			(layer "F.Fab")
		)
		(fp_circle
			(center -0.9652 0.9652)
			(end -0.9144 0.9652)
			(stroke
				(width 0.15)
				(type solid)
			)
			(fill no)
			(layer "F.Fab")
		)
		(fp_text user "License: Apache-2.0"
			(at -1.12 5.024 90)
			(layer "F.Fab")
			(effects
				(font
					(size 0.7 0.7)
					(thickness 0.15)
				)
				(justify right top)
			)
		)
		(fp_text user "Author: Antmicro"
			(at -1.12 6.224 90)
			(layer "F.Fab")
			(effects
				(font
					(size 0.7 0.7)
					(thickness 0.15)
				)
				(justify right top)
			)
		)
		(fp_text user "${REFERENCE}"
			(at -1.12 3.824 90)
			(layer "F.Fab")
			(effects
				(font
					(size 0.7 0.7)
					(thickness 0.15)
				)
				(justify right top)
			)
		)
		(pad "1" smd rect
			(at -0.5 0.65 270)
			(size 0.4 0.51)
			(layers "F.Cu" "F.Mask" "F.Paste")
			(net 883 "Net-(Q10-G)")
			(pinfunction "G")
			(pintype "input")
		)
		(pad "2" smd rect
			(at 0.498 0.65 270)
			(size 0.4 0.51)
			(layers "F.Cu" "F.Mask" "F.Paste")
			(net 1 "GND")
			(pinfunction "S")
			(pintype "passive")
		)
		(pad "3" smd rect
			(at 0 -0.652 270)
			(size 0.4 0.51)
			(layers "F.Cu" "F.Mask" "F.Paste")
			(net 1303 "Net-(Q38-D)")
			(pinfunction "D")
			(pintype "passive")
		)
	)
)
